(kicad_pcb
	(version 20240108)
	(generator "pcbnew")
	(generator_version "8.0")
	(general
		(thickness 1.62)
		(legacy_teardrops no)
	)
	(paper "A4")
	(title_block
		(title "Jetson Orin Baseboard")
		(date "2025-03-12")
		(rev "1.3.4")
		(company "Antmicro Ltd")
		(comment 1 "www.antmicro.com")
		(comment 9 "footprints 65-67 of 677")
	)
	(layers
		(0 "F.Cu" signal)
		(1 "In1.Cu" signal)
		(2 "In2.Cu" signal)
		(3 "In3.Cu" signal)
		(4 "In4.Cu" jumper)
		(5 "In5.Cu" signal)
		(6 "In6.Cu" signal)
		(31 "B.Cu" signal)
		(32 "B.Adhes" user "B.Adhesive")
		(33 "F.Adhes" user "F.Adhesive")
		(34 "B.Paste" user)
		(35 "F.Paste" user)
		(36 "B.SilkS" user "B.Silkscreen")
		(37 "F.SilkS" user "F.Silkscreen")
		(38 "B.Mask" user)
		(39 "F.Mask" user)
		(40 "Dwgs.User" user "User.Drawings")
		(41 "Cmts.User" user "User.Comments")
		(42 "Eco1.User" user "User.Eco1")
		(43 "Eco2.User" user "User.Eco2")
		(44 "Edge.Cuts" user)
		(45 "Margin" user)
		(46 "B.CrtYd" user "B.Courtyard")
		(47 "F.CrtYd" user "F.Courtyard")
		(48 "B.Fab" user)
		(49 "F.Fab" user)
	)
	(footprint "antmicro-footprints:C_0402_1005Metric"
		(layer "F.Cu")
		(at 62.55 102.925 180)
		(descr "Capacitor SMD 0402")
		(tags "capacitor SMD 0402")
		(property "Reference" "C35"
			(at 1.11 -1.325 180)
			(layer "F.SilkS")
			(effects
				(font
					(size 0.7 0.7)
					(thickness 0.15)
				)
				(justify left bottom)
			)
		)
		(property "Value" "C_10u_0402"
			(at -1.022927 2.155213 180)
			(layer "F.Fab")
			(effects
				(font
					(size 0.7 0.7)
					(thickness 0.15)
				)
				(justify left bottom)
			)
		)
		(property "Footprint" "antmicro-footprints:C_0402_1005Metric"
			(at 0 0 180)
			(layer "F.Fab")
			(hide yes)
			(effects
				(font
					(size 1.27 1.27)
					(thickness 0.15)
				)
			)
		)
		(property "Datasheet" "https://www.yageo.com/en/Chart/Download/pdf/CC0402MRX5R5BB106"
			(at 0 0 180)
			(layer "F.Fab")
			(hide yes)
			(effects
				(font
					(size 1.27 1.27)
					(thickness 0.15)
				)
			)
		)
		(property "Author" "Antmicro"
			(at 125.1 205.85 0)
			(layer "F.Fab")
			(hide yes)
			(effects
				(font
					(size 1 1)
					(thickness 0.15)
				)
			)
		)
		(property "Dielectric" ""
			(at 125.1 205.85 0)
			(layer "F.Fab")
			(hide yes)
			(effects
				(font
					(size 1 1)
					(thickness 0.15)
				)
			)
		)
		(property "License" "Apache-2.0"
			(at 125.1 205.85 0)
			(layer "F.Fab")
			(hide yes)
			(effects
				(font
					(size 1 1)
					(thickness 0.15)
				)
			)
		)
		(property "MPN" "CC0402MRX5R5BB106"
			(at 125.1 205.85 0)
			(layer "F.Fab")
			(hide yes)
			(effects
				(font
					(size 1 1)
					(thickness 0.15)
				)
			)
		)
		(property "Manufacturer" "YAGEO"
			(at 125.1 205.85 0)
			(layer "F.Fab")
			(hide yes)
			(effects
				(font
					(size 1 1)
					(thickness 0.15)
				)
			)
		)
		(property "Val" "10u"
			(at 125.1 205.85 0)
			(layer "F.Fab")
			(hide yes)
			(effects
				(font
					(size 1 1)
					(thickness 0.15)
				)
			)
		)
		(property "Voltage" ""
			(at 125.1 205.85 0)
			(layer "F.Fab")
			(hide yes)
			(effects
				(font
					(size 1 1)
					(thickness 0.15)
				)
			)
		)
		(sheetname "USB Debug, DP")
		(sheetfile "usb.kicad_sch")
		(attr smd)
		(fp_rect
			(start -0.925 -0.47)
			(end 0.925 0.47)
			(stroke
				(width 0.05)
				(type default)
			)
			(fill none)
			(layer "F.CrtYd")
		)
		(fp_line
			(start 0.504 0.248)
			(end -0.494 0.248)
			(stroke
				(width 0.15)
				(type solid)
			)
			(layer "F.Fab")
		)
		(fp_line
			(start 0.504 -0.25)
			(end 0.504 0.248)
			(stroke
				(width 0.15)
				(type solid)
			)
			(layer "F.Fab")
		)
		(fp_line
			(start -0.494 0.248)
			(end -0.494 -0.25)
			(stroke
				(width 0.15)
				(type solid)
			)
			(layer "F.Fab")
		)
		(fp_line
			(start -0.494 -0.25)
			(end 0.504 -0.25)
			(stroke
				(width 0.15)
				(type solid)
			)
			(layer "F.Fab")
		)
		(fp_text user "License: Apache-2.0"
			(at -0.939 5.799 180)
			(layer "F.Fab")
			(hide yes)
			(effects
				(font
					(size 0.7 0.7)
					(thickness 0.15)
				)
				(justify left bottom)
			)
		)
		(fp_text user "${REFERENCE}"
			(at -0.939 4.599 180)
			(layer "F.Fab")
			(hide yes)
			(effects
				(font
					(size 0.7 0.7)
					(thickness 0.15)
				)
				(justify left bottom)
			)
		)
		(fp_text user "Author: Antmicro"
			(at -0.939 3.399 180)
			(layer "F.Fab")
			(hide yes)
			(effects
				(font
					(size 0.7 0.7)
					(thickness 0.15)
				)
				(justify left bottom)
			)
		)
		(pad "1" smd roundrect
			(at -0.48 0 180)
			(size 0.59 0.64)
			(layers "F.Cu" "F.Paste" "F.Mask")
			(roundrect_rratio 0.25)
			(net 1 "GND")
			(pintype "passive")
		)
		(pad "2" smd roundrect
			(at 0.48 0 180)
			(size 0.59 0.64)
			(layers "F.Cu" "F.Paste" "F.Mask")
			(roundrect_rratio 0.25)
			(net 99 "+5V")
			(pintype "passive")
		)
	)
	(footprint "antmicro-footprints:Spacer_Drill3.7mm_H2.5mm_9774025151R"
		(layer "F.Cu")
		(at 79.25 95.15)
		(descr "Spacer M=3 h=2.5mm fi=5.1mm")
		(property "Reference" "SP7"
			(at -0.95 4.35 0)
			(layer "F.SilkS")
			(effects
				(font
					(size 0.7 0.7)
					(thickness 0.15)
				)
				(justify left bottom)
			)
		)
		(property "Value" "Spacer_Drill3.7mm_H2.5mm_9774025151R"
			(at -2.75 4.25 0)
			(layer "F.Fab")
			(effects
				(font
					(size 0.7 0.7)
					(thickness 0.15)
				)
				(justify left bottom)
			)
		)
		(property "Footprint" "antmicro-footprints:Spacer_Drill3.7mm_H2.5mm_9774025151R"
			(at 0 0 0)
			(layer "F.Fab")
			(hide yes)
			(effects
				(font
					(size 1.27 1.27)
					(thickness 0.15)
				)
			)
		)
		(property "Datasheet" "https://www.we-online.com/components/products/datasheet/9774025151R.pdf"
			(at 0 0 0)
			(layer "F.Fab")
			(hide yes)
			(effects
				(font
					(size 1.27 1.27)
					(thickness 0.15)
				)
			)
		)
		(property "Author" "Antmicro"
			(at 0 0 0)
			(layer "F.Fab")
			(hide yes)
			(effects
				(font
					(size 1 1)
					(thickness 0.15)
				)
			)
		)
		(property "License" "Apache-2.0"
			(at 0 0 0)
			(layer "F.Fab")
			(hide yes)
			(effects
				(font
					(size 1 1)
					(thickness 0.15)
				)
			)
		)
		(property "MPN" "9774025151R"
			(at 0 0 0)
			(layer "F.Fab")
			(hide yes)
			(effects
				(font
					(size 1 1)
					(thickness 0.15)
				)
			)
		)
		(property "Manufacturer" "Würth Elektronik"
			(at 0 0 0)
			(layer "F.Fab")
			(hide yes)
			(effects
				(font
					(size 1 1)
					(thickness 0.15)
				)
			)
		)
		(sheetname "M.2")
		(sheetfile "m-2.kicad_sch")
		(solder_paste_ratio -1)
		(attr smd)
		(fp_circle
			(center 0 0)
			(end 3.05 0)
			(stroke
				(width 0.05)
				(type solid)
			)
			(fill none)
			(layer "F.CrtYd")
		)
		(fp_circle
			(center 0 0)
			(end 2.6 0)
			(stroke
				(width 0.15)
				(type solid)
			)
			(fill none)
			(layer "F.Fab")
		)
		(fp_text user "${REFERENCE}"
			(at -2.75 5.5 0)
			(layer "F.Fab")
			(hide yes)
			(effects
				(font
					(size 0.7 0.7)
					(thickness 0.15)
				)
				(justify left bottom)
			)
		)
		(fp_text user "License: Apache-2.0"
			(at -2.75 8.25 0)
			(layer "F.Fab")
			(hide yes)
			(effects
				(font
					(size 0.7 0.7)
					(thickness 0.15)
				)
				(justify left bottom)
			)
		)
		(fp_text user "Author: Antmicro"
			(at -2.75 6.75 0)
			(layer "F.Fab")
			(hide yes)
			(effects
				(font
					(size 0.7 0.7)
					(thickness 0.15)
				)
				(justify left bottom)
			)
		)
		(pad "" smd custom
			(at -1.7 -1.7)
			(size 0.62 0.62)
			(layers "F.Paste")
			(thermal_bridge_angle 90)
			(options
				(clearance outline)
				(anchor circle)
			)
			(primitives
				(gr_arc
					(start -0.250195 1.279127)
					(mid 0.285453 0.294389)
					(end 1.266786 -0.24747)
					(width 0.2)
				)
				(gr_arc
					(start -0.34334 1.279127)
					(mid 0.218448 0.232562)
					(end 1.259603 -0.339191)
					(width 0.2)
				)
				(gr_arc
					(start -0.436309 1.279127)
					(mid 0.152481 0.169693)
					(end 1.255279 -0.431435)
					(width 0.2)
				)
				(gr_arc
					(start -0.529126 1.279127)
					(mid 0.087543 0.105785)
					(end 1.253811 -0.524161)
					(width 0.2)
				)
				(gr_arc
					(start -0.621807 1.279127)
					(mid 0.0309 0.033527)
					(end 1.275473 -0.621136)
					(width 0.2)
				)
				(gr_arc
					(start -0.71437 1.279127)
					(mid -0.037759 -0.026651)
					(end 1.263664 -0.711602)
					(width 0.2)
				)
				(gr_arc
					(start -0.806826 1.279127)
					(mid -0.105837 -0.087395)
					(end 1.253435 -0.802342)
					(width 0.2)
				)
				(gr_arc
					(start -0.899187 1.279127)
					(mid -0.165236 -0.156885)
					(end 1.267475 -0.897258)
					(width 0.2)
				)
				(gr_arc
					(start -0.991463 1.279127)
					(mid -0.228522 -0.222449)
					(end 1.270645 -0.990112)
					(width 0.2)
				)
				(gr_arc
					(start -1.083663 1.279127)
					(mid -0.294507 -0.285313)
					(end 1.266278 -1.081674)
					(width 0.2)
				)
				(gr_line
					(start 1.279127 -0.250195)
					(end 1.279127 -1.083663)
					(width 0.2)
				)
				(gr_line
					(start -0.250195 1.279127)
					(end -1.083663 1.279127)
					(width 0.2)
				)
			)
		)
		(pad "" smd custom
			(at -1.7 1.7 90)
			(size 0.62 0.62)
			(layers "F.Paste")
			(thermal_bridge_angle 90)
			(options
				(clearance outline)
				(anchor circle)
			)
			(primitives
				(gr_arc
					(start -0.250195 1.279127)
					(mid 0.285453 0.294389)
					(end 1.266786 -0.24747)
					(width 0.2)
				)
				(gr_arc
					(start -0.34334 1.279127)
					(mid 0.218448 0.232562)
					(end 1.259603 -0.339191)
					(width 0.2)
				)
				(gr_arc
					(start -0.436309 1.279127)
					(mid 0.152481 0.169693)
					(end 1.255279 -0.431435)
					(width 0.2)
				)
				(gr_arc
					(start -0.529126 1.279127)
					(mid 0.087543 0.105785)
					(end 1.253811 -0.524161)
					(width 0.2)
				)
				(gr_arc
					(start -0.621807 1.279127)
					(mid 0.0309 0.033527)
					(end 1.275473 -0.621136)
					(width 0.2)
				)
				(gr_arc
					(start -0.71437 1.279127)
					(mid -0.037759 -0.026651)
					(end 1.263664 -0.711602)
					(width 0.2)
				)
				(gr_arc
					(start -0.806826 1.279127)
					(mid -0.105837 -0.087395)
					(end 1.253435 -0.802342)
					(width 0.2)
				)
				(gr_arc
					(start -0.899187 1.279127)
					(mid -0.165236 -0.156885)
					(end 1.267475 -0.897258)
					(width 0.2)
				)
				(gr_arc
					(start -0.991463 1.279127)
					(mid -0.228522 -0.222449)
					(end 1.270645 -0.990112)
					(width 0.2)
				)
				(gr_arc
					(start -1.083663 1.279127)
					(mid -0.294507 -0.285313)
					(end 1.266278 -1.081674)
					(width 0.2)
				)
				(gr_line
					(start 1.279127 -0.250195)
					(end 1.279127 -1.083663)
					(width 0.2)
				)
				(gr_line
					(start -0.250195 1.279127)
					(end -1.083663 1.279127)
					(width 0.2)
				)
			)
		)
		(pad "" smd custom
			(at 1.7 -1.7 270)
			(size 0.62 0.62)
			(layers "F.Paste")
			(thermal_bridge_angle 90)
			(options
				(clearance outline)
				(anchor circle)
			)
			(primitives
				(gr_arc
					(start -0.250195 1.279127)
					(mid 0.285453 0.294389)
					(end 1.266786 -0.24747)
					(width 0.2)
				)
				(gr_arc
					(start -0.34334 1.279127)
					(mid 0.218448 0.232562)
					(end 1.259603 -0.339191)
					(width 0.2)
				)
				(gr_arc
					(start -0.436309 1.279127)
					(mid 0.152481 0.169693)
					(end 1.255279 -0.431435)
					(width 0.2)
				)
				(gr_arc
					(start -0.529126 1.279127)
					(mid 0.087543 0.105785)
					(end 1.253811 -0.524161)
					(width 0.2)
				)
				(gr_arc
					(start -0.621807 1.279127)
					(mid 0.0309 0.033527)
					(end 1.275473 -0.621136)
					(width 0.2)
				)
				(gr_arc
					(start -0.71437 1.279127)
					(mid -0.037759 -0.026651)
					(end 1.263664 -0.711602)
					(width 0.2)
				)
				(gr_arc
					(start -0.806826 1.279127)
					(mid -0.105837 -0.087395)
					(end 1.253435 -0.802342)
					(width 0.2)
				)
				(gr_arc
					(start -0.899187 1.279127)
					(mid -0.165236 -0.156885)
					(end 1.267475 -0.897258)
					(width 0.2)
				)
				(gr_arc
					(start -0.991463 1.279127)
					(mid -0.228522 -0.222449)
					(end 1.270645 -0.990112)
					(width 0.2)
				)
				(gr_arc
					(start -1.083663 1.279127)
					(mid -0.294507 -0.285313)
					(end 1.266278 -1.081674)
					(width 0.2)
				)
				(gr_line
					(start 1.279127 -0.250195)
					(end 1.279127 -1.083663)
					(width 0.2)
				)
				(gr_line
					(start -0.250195 1.279127)
					(end -1.083663 1.279127)
					(width 0.2)
				)
			)
		)
		(pad "" smd custom
			(at 1.7 1.7 180)
			(size 0.62 0.62)
			(layers "F.Paste")
			(thermal_bridge_angle 90)
			(options
				(clearance outline)
				(anchor circle)
			)
			(primitives
				(gr_arc
					(start -0.250195 1.279127)
					(mid 0.285453 0.294389)
					(end 1.266786 -0.24747)
					(width 0.2)
				)
				(gr_arc
					(start -0.34334 1.279127)
					(mid 0.218448 0.232562)
					(end 1.259603 -0.339191)
					(width 0.2)
				)
				(gr_arc
					(start -0.436309 1.279127)
					(mid 0.152481 0.169693)
					(end 1.255279 -0.431435)
					(width 0.2)
				)
				(gr_arc
					(start -0.529126 1.279127)
					(mid 0.087543 0.105785)
					(end 1.253811 -0.524161)
					(width 0.2)
				)
				(gr_arc
					(start -0.621807 1.279127)
					(mid 0.0309 0.033527)
					(end 1.275473 -0.621136)
					(width 0.2)
				)
				(gr_arc
					(start -0.71437 1.279127)
					(mid -0.037759 -0.026651)
					(end 1.263664 -0.711602)
					(width 0.2)
				)
				(gr_arc
					(start -0.806826 1.279127)
					(mid -0.105837 -0.087395)
					(end 1.253435 -0.802342)
					(width 0.2)
				)
				(gr_arc
					(start -0.899187 1.279127)
					(mid -0.165236 -0.156885)
					(end 1.267475 -0.897258)
					(width 0.2)
				)
				(gr_arc
					(start -0.991463 1.279127)
					(mid -0.228522 -0.222449)
					(end 1.270645 -0.990112)
					(width 0.2)
				)
				(gr_arc
					(start -1.083663 1.279127)
					(mid -0.294507 -0.285313)
					(end 1.266278 -1.081674)
					(width 0.2)
				)
				(gr_line
					(start 1.279127 -0.250195)
					(end 1.279127 -1.083663)
					(width 0.2)
				)
				(gr_line
					(start -0.250195 1.279127)
					(end -1.083663 1.279127)
					(width 0.2)
				)
			)
		)
		(pad "1" thru_hole circle
			(at 0 0)
			(size 6 6)
			(drill 3.7)
			(layers "*.Cu" "*.Mask")
			(remove_unused_layers no)
			(net 1 "GND")
			(pintype "passive")
		)
	)
	(footprint "antmicro-footprints:C_0402_1005Metric"
		(layer "F.Cu")
		(at 75.42 86.34)
		(descr "Capacitor SMD 0402")
		(tags "capacitor SMD 0402")
		(property "Reference" "C125"
			(at -2.097516 -2.367303 0)
			(layer "F.SilkS")
			(effects
				(font
					(size 0.7 0.7)
					(thickness 0.15)
				)
				(justify left bottom)
			)
		)
		(property "Value" "C_100n_0402"
			(at -1.022927 2.155213 0)
			(layer "F.Fab")
			(effects
				(font
					(size 0.7 0.7)
					(thickness 0.15)
				)
				(justify left bottom)
			)
		)
		(property "Footprint" "antmicro-footprints:C_0402_1005Metric"
			(at 0 0 0)
			(layer "F.Fab")
			(hide yes)
			(effects
				(font
					(size 1.27 1.27)
					(thickness 0.15)
				)
			)
		)
		(property "Datasheet" "https://www.murata.com/products/productdetail?partno=GRM155R61H104KE14%23"
			(at 0 0 0)
			(layer "F.Fab")
			(hide yes)
			(effects
				(font
					(size 1.27 1.27)
					(thickness 0.15)
				)
			)
		)
		(property "Author" "Antmicro"
			(at 0 0 0)
			(layer "F.Fab")
			(hide yes)
			(effects
				(font
					(size 1 1)
					(thickness 0.15)
				)
			)
		)
		(property "Dielectric" "X5R"
			(at 0 0 0)
			(layer "F.Fab")
			(hide yes)
			(effects
				(font
					(size 1 1)
					(thickness 0.15)
				)
			)
		)
		(property "License" "Apache-2.0"
			(at 0 0 0)
			(layer "F.Fab")
			(hide yes)
			(effects
				(font
					(size 1 1)
					(thickness 0.15)
				)
			)
		)
		(property "MPN" "GRM155R61H104KE14D"
			(at 0 0 0)
			(layer "F.Fab")
			(hide yes)
			(effects
				(font
					(size 1 1)
					(thickness 0.15)
				)
			)
		)
		(property "Manufacturer" "Murata"
			(at 0 0 0)
			(layer "F.Fab")
			(hide yes)
			(effects
				(font
					(size 1 1)
					(thickness 0.15)
				)
			)
		)
		(property "Val" "100n"
			(at 0 0 0)
			(layer "F.Fab")
			(hide yes)
			(effects
				(font
					(size 1 1)
					(thickness 0.15)
				)
			)
		)
		(property "Voltage" "50V"
			(at 0 0 0)
			(layer "F.Fab")
			(hide yes)
			(effects
				(font
					(size 1 1)
					(thickness 0.15)
				)
			)
		)
		(sheetname "Supply")
		(sheetfile "supply.kicad_sch")
		(attr smd)
		(fp_rect
			(start -0.925 -0.47)
			(end 0.925 0.47)
			(stroke
				(width 0.05)
				(type default)
			)
			(fill none)
			(layer "F.CrtYd")
		)
		(fp_line
			(start -0.494 -0.25)
			(end 0.504 -0.25)
			(stroke
				(width 0.15)
				(type solid)
			)
			(layer "F.Fab")
		)
		(fp_line
			(start -0.494 0.248)
			(end -0.494 -0.25)
			(stroke
				(width 0.15)
				(type solid)
			)
			(layer "F.Fab")
		)
		(fp_line
			(start 0.504 -0.25)
			(end 0.504 0.248)
			(stroke
				(width 0.15)
				(type solid)
			)
			(layer "F.Fab")
		)
		(fp_line
			(start 0.504 0.248)
			(end -0.494 0.248)
			(stroke
				(width 0.15)
				(type solid)
			)
			(layer "F.Fab")
		)
		(fp_text user "License: Apache-2.0"
			(at -0.939 5.799 0)
			(layer "F.Fab")
			(hide yes)
			(effects
				(font
					(size 0.7 0.7)
					(thickness 0.15)
				)
				(justify left bottom)
			)
		)
		(fp_text user "Author: Antmicro"
			(at -0.939 3.399 0)
			(layer "F.Fab")
			(hide yes)
			(effects
				(font
					(size 0.7 0.7)
					(thickness 0.15)
				)
				(justify left bottom)
			)
		)
		(fp_text user "${REFERENCE}"
			(at -0.939 4.599 0)
			(layer "F.Fab")
			(hide yes)
			(effects
				(font
					(size 0.7 0.7)
					(thickness 0.15)
				)
				(justify left bottom)
			)
		)
		(pad "1" smd roundrect
			(at -0.48 0)
			(size 0.59 0.64)
			(layers "F.Cu" "F.Paste" "F.Mask")
			(roundrect_rratio 0.25)
			(net 758 "/Supply/3V3_PHASE")
			(pintype "passive")
		)
		(pad "2" smd roundrect
			(at 0.48 0)
			(size 0.59 0.64)
			(layers "F.Cu" "F.Paste" "F.Mask")
			(roundrect_rratio 0.25)
			(net 358 "/Supply/3V3_BOOT")
			(pintype "passive")
		)
	)
)
